(kicad_pcb
	(version 20260206)
	(generator "pcbnew")
	(generator_version "10.0")
	(general
		(thickness 1.6)
		(legacy_teardrops no)
	)
	(paper "A4")
	(title_block
		(title "Wiwynn_Tioga_Pass_MB.brd")
		(comment 1 "Tioga Pass / footprint 3254 of 4770 (J6M1), pads 1-123 of 291")
	)
	(layers
		(0 "F.Cu" signal "TOP")
		(4 "In1.Cu" signal "L2GND")
		(6 "In2.Cu" signal "L3")
		(8 "In3.Cu" signal "L4GND")
		(10 "In4.Cu" signal "L5")
		(12 "In5.Cu" signal "L6GND")
		(14 "In6.Cu" signal "L7VCC")
		(16 "In7.Cu" signal "L8VCC")
		(18 "In8.Cu" signal "L9GND")
		(20 "In9.Cu" signal "L10")
		(22 "In10.Cu" signal "L11GND")
		(24 "In11.Cu" signal "L12")
		(26 "In12.Cu" signal "L13GND")
		(2 "B.Cu" signal "BOTTOM")
		(9 "F.Adhes" user "F.Adhesive")
		(11 "B.Adhes" user "B.Adhesive")
		(13 "F.Paste" user "Package Geometry/Pastemask Top")
		(15 "B.Paste" user "Package Geometry/Pastemask Bottom")
		(5 "F.SilkS" user "Ref Des/Silkscreen Top")
		(7 "B.SilkS" user "Ref Des/Silkscreen Bottom")
		(1 "F.Mask" user "Board Geometry/Soldermask Top")
		(3 "B.Mask" user "Board Geometry/Soldermask Bottom")
		(17 "Dwgs.User" user "User.Drawings")
		(19 "Cmts.User" user "User.Comments")
		(21 "Eco1.User" user "User.Eco1")
		(23 "Eco2.User" user "User.Eco2")
		(25 "Edge.Cuts" user "Board Geometry/Outline")
		(27 "Margin" user)
		(31 "F.CrtYd" user "Package Geometry/Place Bound Top")
		(29 "B.CrtYd" user "Package Geometry/Place Bound Bottom")
		(35 "F.Fab" user "Ref Des/Assembly Top")
		(33 "B.Fab" user "Ref Des/Assembly Bottom")
	)
	(footprint ""
		(layer "B.Cu")
		(at 194.700398 -132.876036 90)
		(property "Reference" "J6M1"
			(at 2.352548 37.96411 0)
			(unlocked yes)
			(layer "B.SilkS")
			(effects
				(font
					(size 0.7874 0.5842)
					(thickness 0.1524)
				)
				(justify left mirror)
			)
		)
		(property "Value" ""
			(at 0 0 90)
			(layer "B.Fab")
			(effects
				(font
					(size 1.27 1.27)
				)
				(justify mirror)
			)
		)
		(duplicate_pad_numbers_are_jumpers no)
		(pad "" thru_hole circle
			(at -2.29997 -5.649976 270)
			(size 2.8194 2.8194)
			(drill 2.4384)
			(layers "*.Cu" "*.Mask")
			(remove_unused_layers no)
			(clearance 0.127)
			(thermal_gap 0.127)
		)
		(pad "" thru_hole oval
			(at -2.29997 68.90004 270)
			(size 2.8194 1.5748)
			(drill oval 2.4384 1.1938)
			(layers "*.Cu" "*.Mask")
			(remove_unused_layers no)
			(clearance 0.127)
			(thermal_gap 0.127)
		)
		(pad "" thru_hole circle
			(at -2.29997 132.299964 270)
			(size 2.8194 2.8194)
			(drill 2.4384)
			(layers "*.Cu" "*.Mask")
			(remove_unused_layers no)
			(clearance 0.127)
			(thermal_gap 0.127)
		)
		(pad "1" smd rect
			(at 0 0 270)
			(size 1.8034 0.508)
			(layers "B.Cu" "B.Mask" "B.Paste")
			(net "P12V_NVDIMM_DEF")
		)
		(pad "2" smd rect
			(at 0 0.849884 270)
			(size 1.8034 0.508)
			(layers "B.Cu" "B.Mask" "B.Paste")
			(net "GND")
		)
		(pad "3" smd rect
			(at 0 1.700022 270)
			(size 1.8034 0.508)
			(layers "B.Cu" "B.Mask" "B.Paste")
			(net "M_D_DQ<4>")
		)
		(pad "4" smd rect
			(at 0 2.549906 270)
			(size 1.8034 0.508)
			(layers "B.Cu" "B.Mask" "B.Paste")
			(net "GND")
		)
		(pad "5" smd rect
			(at 0 3.400044 270)
			(size 1.8034 0.508)
			(layers "B.Cu" "B.Mask" "B.Paste")
			(net "M_D_DQ<0>")
		)
		(pad "6" smd rect
			(at 0 4.249928 270)
			(size 1.8034 0.508)
			(layers "B.Cu" "B.Mask" "B.Paste")
			(net "GND")
		)
		(pad "7" smd rect
			(at 0 5.100066 270)
			(size 1.8034 0.508)
			(layers "B.Cu" "B.Mask" "B.Paste")
			(net "M_D_DQS_DP<9>")
		)
		(pad "8" smd rect
			(at 0 5.94995 270)
			(size 1.8034 0.508)
			(layers "B.Cu" "B.Mask" "B.Paste")
			(net "M_D_DQS_DN<9>")
		)
		(pad "9" smd rect
			(at 0 6.800088 270)
			(size 1.8034 0.508)
			(layers "B.Cu" "B.Mask" "B.Paste")
			(net "GND")
		)
		(pad "10" smd rect
			(at 0 7.649972 270)
			(size 1.8034 0.508)
			(layers "B.Cu" "B.Mask" "B.Paste")
			(net "M_D_DQ<6>")
		)
		(pad "11" smd rect
			(at 0 8.50011 270)
			(size 1.8034 0.508)
			(layers "B.Cu" "B.Mask" "B.Paste")
			(net "GND")
		)
		(pad "12" smd rect
			(at 0 9.349994 270)
			(size 1.8034 0.508)
			(layers "B.Cu" "B.Mask" "B.Paste")
			(net "M_D_DQ<2>")
		)
		(pad "13" smd rect
			(at 0 10.199878 270)
			(size 1.8034 0.508)
			(layers "B.Cu" "B.Mask" "B.Paste")
			(net "GND")
		)
		(pad "14" smd rect
			(at 0 11.050016 270)
			(size 1.8034 0.508)
			(layers "B.Cu" "B.Mask" "B.Paste")
			(net "M_D_DQ<12>")
		)
		(pad "15" smd rect
			(at 0 11.8999 270)
			(size 1.8034 0.508)
			(layers "B.Cu" "B.Mask" "B.Paste")
			(net "GND")
		)
		(pad "16" smd rect
			(at 0 12.750038 270)
			(size 1.8034 0.508)
			(layers "B.Cu" "B.Mask" "B.Paste")
			(net "M_D_DQ<8>")
		)
		(pad "17" smd rect
			(at 0 13.599922 270)
			(size 1.8034 0.508)
			(layers "B.Cu" "B.Mask" "B.Paste")
			(net "GND")
		)
		(pad "18" smd rect
			(at 0 14.45006 270)
			(size 1.8034 0.508)
			(layers "B.Cu" "B.Mask" "B.Paste")
			(net "M_D_DQS_DP<10>")
		)
		(pad "19" smd rect
			(at 0 15.299944 270)
			(size 1.8034 0.508)
			(layers "B.Cu" "B.Mask" "B.Paste")
			(net "M_D_DQS_DN<10>")
		)
		(pad "20" smd rect
			(at 0 16.150082 270)
			(size 1.8034 0.508)
			(layers "B.Cu" "B.Mask" "B.Paste")
			(net "GND")
		)
		(pad "21" smd rect
			(at 0 16.999966 270)
			(size 1.8034 0.508)
			(layers "B.Cu" "B.Mask" "B.Paste")
			(net "M_D_DQ<14>")
		)
		(pad "22" smd rect
			(at 0 17.850104 270)
			(size 1.8034 0.508)
			(layers "B.Cu" "B.Mask" "B.Paste")
			(net "GND")
		)
		(pad "23" smd rect
			(at 0 18.699988 270)
			(size 1.8034 0.508)
			(layers "B.Cu" "B.Mask" "B.Paste")
			(net "M_D_DQ<10>")
		)
		(pad "24" smd rect
			(at 0 19.550126 270)
			(size 1.8034 0.508)
			(layers "B.Cu" "B.Mask" "B.Paste")
			(net "GND")
		)
		(pad "25" smd rect
			(at 0 20.40001 270)
			(size 1.8034 0.508)
			(layers "B.Cu" "B.Mask" "B.Paste")
			(net "M_D_DQ<20>")
		)
		(pad "26" smd rect
			(at 0 21.249894 270)
			(size 1.8034 0.508)
			(layers "B.Cu" "B.Mask" "B.Paste")
			(net "GND")
		)
		(pad "27" smd rect
			(at 0 22.100032 270)
			(size 1.8034 0.508)
			(layers "B.Cu" "B.Mask" "B.Paste")
			(net "M_D_DQ<16>")
		)
		(pad "28" smd rect
			(at 0 22.949916 270)
			(size 1.8034 0.508)
			(layers "B.Cu" "B.Mask" "B.Paste")
			(net "GND")
		)
		(pad "29" smd rect
			(at 0 23.800054 270)
			(size 1.8034 0.508)
			(layers "B.Cu" "B.Mask" "B.Paste")
			(net "M_D_DQS_DP<11>")
		)
		(pad "30" smd rect
			(at 0 24.649938 270)
			(size 1.8034 0.508)
			(layers "B.Cu" "B.Mask" "B.Paste")
			(net "M_D_DQS_DN<11>")
		)
		(pad "31" smd rect
			(at 0 25.500076 270)
			(size 1.8034 0.508)
			(layers "B.Cu" "B.Mask" "B.Paste")
			(net "GND")
		)
		(pad "32" smd rect
			(at 0 26.34996 270)
			(size 1.8034 0.508)
			(layers "B.Cu" "B.Mask" "B.Paste")
			(net "M_D_DQ<22>")
		)
		(pad "33" smd rect
			(at 0 27.200098 270)
			(size 1.8034 0.508)
			(layers "B.Cu" "B.Mask" "B.Paste")
			(net "GND")
		)
		(pad "34" smd rect
			(at 0 28.049982 270)
			(size 1.8034 0.508)
			(layers "B.Cu" "B.Mask" "B.Paste")
			(net "M_D_DQ<18>")
		)
		(pad "35" smd rect
			(at 0 28.90012 270)
			(size 1.8034 0.508)
			(layers "B.Cu" "B.Mask" "B.Paste")
			(net "GND")
		)
		(pad "36" smd rect
			(at 0 29.750004 270)
			(size 1.8034 0.508)
			(layers "B.Cu" "B.Mask" "B.Paste")
			(net "M_D_DQ<28>")
		)
		(pad "37" smd rect
			(at 0 30.599888 270)
			(size 1.8034 0.508)
			(layers "B.Cu" "B.Mask" "B.Paste")
			(net "GND")
		)
		(pad "38" smd rect
			(at 0 31.450026 270)
			(size 1.8034 0.508)
			(layers "B.Cu" "B.Mask" "B.Paste")
			(net "M_D_DQ<24>")
		)
		(pad "39" smd rect
			(at 0 32.29991 270)
			(size 1.8034 0.508)
			(layers "B.Cu" "B.Mask" "B.Paste")
			(net "GND")
		)
		(pad "40" smd rect
			(at 0 33.150048 270)
			(size 1.8034 0.508)
			(layers "B.Cu" "B.Mask" "B.Paste")
			(net "M_D_DQS_DP<12>")
		)
		(pad "41" smd rect
			(at 0 33.999932 270)
			(size 1.8034 0.508)
			(layers "B.Cu" "B.Mask" "B.Paste")
			(net "M_D_DQS_DN<12>")
		)
		(pad "42" smd rect
			(at 0 34.85007 270)
			(size 1.8034 0.508)
			(layers "B.Cu" "B.Mask" "B.Paste")
			(net "GND")
		)
		(pad "43" smd rect
			(at 0 35.699954 270)
			(size 1.8034 0.508)
			(layers "B.Cu" "B.Mask" "B.Paste")
			(net "M_D_DQ<30>")
		)
		(pad "44" smd rect
			(at 0 36.550092 270)
			(size 1.8034 0.508)
			(layers "B.Cu" "B.Mask" "B.Paste")
			(net "GND")
		)
		(pad "45" smd rect
			(at 0 37.399976 270)
			(size 1.8034 0.508)
			(layers "B.Cu" "B.Mask" "B.Paste")
			(net "M_D_DQ<26>")
		)
		(pad "46" smd rect
			(at 0 38.250114 270)
			(size 1.8034 0.508)
			(layers "B.Cu" "B.Mask" "B.Paste")
			(net "GND")
		)
		(pad "47" smd rect
			(at 0 39.099998 270)
			(size 1.8034 0.508)
			(layers "B.Cu" "B.Mask" "B.Paste")
			(net "M_D_ECC<4>")
		)
		(pad "48" smd rect
			(at 0 39.949882 270)
			(size 1.8034 0.508)
			(layers "B.Cu" "B.Mask" "B.Paste")
			(net "GND")
		)
		(pad "49" smd rect
			(at 0 40.80002 270)
			(size 1.8034 0.508)
			(layers "B.Cu" "B.Mask" "B.Paste")
			(net "M_D_ECC<0>")
		)
		(pad "50" smd rect
			(at 0 41.649904 270)
			(size 1.8034 0.508)
			(layers "B.Cu" "B.Mask" "B.Paste")
			(net "GND")
		)
		(pad "51" smd rect
			(at 0 42.500042 270)
			(size 1.8034 0.508)
			(layers "B.Cu" "B.Mask" "B.Paste")
			(net "M_D_DQS_DP<17>")
		)
		(pad "52" smd rect
			(at 0 43.349926 270)
			(size 1.8034 0.508)
			(layers "B.Cu" "B.Mask" "B.Paste")
			(net "M_D_DQS_DN<17>")
		)
		(pad "53" smd rect
			(at 0 44.200064 270)
			(size 1.8034 0.508)
			(layers "B.Cu" "B.Mask" "B.Paste")
			(net "GND")
		)
		(pad "54" smd rect
			(at 0 45.049948 270)
			(size 1.8034 0.508)
			(layers "B.Cu" "B.Mask" "B.Paste")
			(net "M_D_ECC<6>")
		)
		(pad "55" smd rect
			(at 0 45.900086 270)
			(size 1.8034 0.508)
			(layers "B.Cu" "B.Mask" "B.Paste")
			(net "GND")
		)
		(pad "56" smd rect
			(at 0 46.74997 270)
			(size 1.8034 0.508)
			(layers "B.Cu" "B.Mask" "B.Paste")
			(net "M_D_ECC<2>")
		)
		(pad "57" smd rect
			(at 0 47.600108 270)
			(size 1.8034 0.508)
			(layers "B.Cu" "B.Mask" "B.Paste")
			(net "GND")
		)
		(pad "58" smd rect
			(at 0 48.449992 270)
			(size 1.8034 0.508)
			(layers "B.Cu" "B.Mask" "B.Paste")
			(net "M_DEF_RST_N")
		)
		(pad "59" smd rect
			(at 0 49.299876 270)
			(size 1.8034 0.508)
			(layers "B.Cu" "B.Mask" "B.Paste")
			(net "PVDDQ_DEF")
		)
		(pad "60" smd rect
			(at 0 50.150014 270)
			(size 1.8034 0.508)
			(layers "B.Cu" "B.Mask" "B.Paste")
			(net "M_D_CKE<2>")
		)
		(pad "61" smd rect
			(at 0 50.999898 270)
			(size 1.8034 0.508)
			(layers "B.Cu" "B.Mask" "B.Paste")
			(net "PVDDQ_DEF")
		)
		(pad "62" smd rect
			(at 0 51.850036 270)
			(size 1.8034 0.508)
			(layers "B.Cu" "B.Mask" "B.Paste")
			(net "M_D_ACT_N")
		)
		(pad "63" smd rect
			(at 0 52.69992 270)
			(size 1.8034 0.508)
			(layers "B.Cu" "B.Mask" "B.Paste")
			(net "M_D_BG<0>")
		)
		(pad "64" smd rect
			(at 0 53.550058 270)
			(size 1.8034 0.508)
			(layers "B.Cu" "B.Mask" "B.Paste")
			(net "PVDDQ_DEF")
		)
		(pad "65" smd rect
			(at 0 54.399942 270)
			(size 1.8034 0.508)
			(layers "B.Cu" "B.Mask" "B.Paste")
			(net "M_D_MA<12>")
		)
		(pad "66" smd rect
			(at 0 55.25008 270)
			(size 1.8034 0.508)
			(layers "B.Cu" "B.Mask" "B.Paste")
			(net "M_D_MA<9>")
		)
		(pad "67" smd rect
			(at 0 56.099964 270)
			(size 1.8034 0.508)
			(layers "B.Cu" "B.Mask" "B.Paste")
			(net "PVDDQ_DEF")
		)
		(pad "68" smd rect
			(at 0 56.950102 270)
			(size 1.8034 0.508)
			(layers "B.Cu" "B.Mask" "B.Paste")
			(net "M_D_MA<8>")
		)
		(pad "69" smd rect
			(at 0 57.799986 270)
			(size 1.8034 0.508)
			(layers "B.Cu" "B.Mask" "B.Paste")
			(net "M_D_MA<6>")
		)
		(pad "70" smd rect
			(at 0 58.650124 270)
			(size 1.8034 0.508)
			(layers "B.Cu" "B.Mask" "B.Paste")
			(net "PVDDQ_DEF")
		)
		(pad "71" smd rect
			(at 0 59.500008 270)
			(size 1.8034 0.508)
			(layers "B.Cu" "B.Mask" "B.Paste")
			(net "M_D_MA<3>")
		)
		(pad "72" smd rect
			(at 0 60.349892 270)
			(size 1.8034 0.508)
			(layers "B.Cu" "B.Mask" "B.Paste")
			(net "M_D_MA<1>")
		)
		(pad "73" smd rect
			(at 0 61.20003 270)
			(size 1.8034 0.508)
			(layers "B.Cu" "B.Mask" "B.Paste")
			(net "PVDDQ_DEF")
		)
		(pad "74" smd rect
			(at 0 62.049914 270)
			(size 1.8034 0.508)
			(layers "B.Cu" "B.Mask" "B.Paste")
			(net "M_D_CLK_DP<2>")
		)
		(pad "75" smd rect
			(at 0 62.900052 270)
			(size 1.8034 0.508)
			(layers "B.Cu" "B.Mask" "B.Paste")
			(net "M_D_CLK_DN<2>")
		)
		(pad "76" smd rect
			(at 0 63.749936 270)
			(size 1.8034 0.508)
			(layers "B.Cu" "B.Mask" "B.Paste")
			(net "PVDDQ_DEF")
		)
		(pad "77" smd rect
			(at 0 64.600074 270)
			(size 1.8034 0.508)
			(layers "B.Cu" "B.Mask" "B.Paste")
			(net "PVTT_DEF")
		)
		(pad "78" smd rect
			(at 0 70.550024 270)
			(size 1.8034 0.508)
			(layers "B.Cu" "B.Mask" "B.Paste")
			(net "FM_DIMM_EVENT_COD_N")
		)
		(pad "79" smd rect
			(at 0 71.399908 270)
			(size 1.8034 0.508)
			(layers "B.Cu" "B.Mask" "B.Paste")
			(net "M_D_MA<0>")
		)
		(pad "80" smd rect
			(at 0 72.250046 270)
			(size 1.8034 0.508)
			(layers "B.Cu" "B.Mask" "B.Paste")
			(net "PVDDQ_DEF")
		)
		(pad "81" smd rect
			(at 0 73.09993 270)
			(size 1.8034 0.508)
			(layers "B.Cu" "B.Mask" "B.Paste")
			(net "M_D_BA<0>")
		)
		(pad "82" smd rect
			(at 0 73.950068 270)
			(size 1.8034 0.508)
			(layers "B.Cu" "B.Mask" "B.Paste")
			(net "M_D_MA<16>")
		)
		(pad "83" smd rect
			(at 0 74.799952 270)
			(size 1.8034 0.508)
			(layers "B.Cu" "B.Mask" "B.Paste")
			(net "PVDDQ_DEF")
		)
		(pad "84" smd rect
			(at 0 75.65009 270)
			(size 1.8034 0.508)
			(layers "B.Cu" "B.Mask" "B.Paste")
			(net "M_D_CS_N<4>")
		)
		(pad "85" smd rect
			(at 0 76.499974 270)
			(size 1.8034 0.508)
			(layers "B.Cu" "B.Mask" "B.Paste")
			(net "PVDDQ_DEF")
		)
		(pad "86" smd rect
			(at 0 77.350112 270)
			(size 1.8034 0.508)
			(layers "B.Cu" "B.Mask" "B.Paste")
			(net "M_D_MA<15>")
		)
		(pad "87" smd rect
			(at 0 78.199996 270)
			(size 1.8034 0.508)
			(layers "B.Cu" "B.Mask" "B.Paste")
			(net "M_D_ODT<2>")
		)
		(pad "88" smd rect
			(at 0 79.04988 270)
			(size 1.8034 0.508)
			(layers "B.Cu" "B.Mask" "B.Paste")
			(net "PVDDQ_DEF")
		)
		(pad "89" smd rect
			(at 0 79.900018 270)
			(size 1.8034 0.508)
			(layers "B.Cu" "B.Mask" "B.Paste")
			(net "M_D_CS_N<5>")
		)
		(pad "90" smd rect
			(at 0 80.749902 270)
			(size 1.8034 0.508)
			(layers "B.Cu" "B.Mask" "B.Paste")
			(net "PVDDQ_DEF")
		)
		(pad "91" smd rect
			(at 0 81.60004 270)
			(size 1.8034 0.508)
			(layers "B.Cu" "B.Mask" "B.Paste")
			(net "M_D_ODT<3>")
		)
		(pad "92" smd rect
			(at 0 82.449924 270)
			(size 1.8034 0.508)
			(layers "B.Cu" "B.Mask" "B.Paste")
			(net "PVDDQ_DEF")
		)
		(pad "93" smd rect
			(at 0 83.300062 270)
			(size 1.8034 0.508)
			(layers "B.Cu" "B.Mask" "B.Paste")
			(net "M_D_CS_N<6>")
		)
		(pad "94" smd rect
			(at 0 84.149946 270)
			(size 1.8034 0.508)
			(layers "B.Cu" "B.Mask" "B.Paste")
			(net "GND")
		)
		(pad "95" smd rect
			(at 0 85.000084 270)
			(size 1.8034 0.508)
			(layers "B.Cu" "B.Mask" "B.Paste")
			(net "M_D_DQ<36>")
		)
		(pad "96" smd rect
			(at 0 85.849968 270)
			(size 1.8034 0.508)
			(layers "B.Cu" "B.Mask" "B.Paste")
			(net "GND")
		)
		(pad "97" smd rect
			(at 0 86.700106 270)
			(size 1.8034 0.508)
			(layers "B.Cu" "B.Mask" "B.Paste")
			(net "M_D_DQ<32>")
		)
		(pad "98" smd rect
			(at 0 87.54999 270)
			(size 1.8034 0.508)
			(layers "B.Cu" "B.Mask" "B.Paste")
			(net "GND")
		)
		(pad "99" smd rect
			(at 0 88.399874 270)
			(size 1.8034 0.508)
			(layers "B.Cu" "B.Mask" "B.Paste")
			(net "M_D_DQS_DP<13>")
		)
		(pad "100" smd rect
			(at 0 89.250012 270)
			(size 1.8034 0.508)
			(layers "B.Cu" "B.Mask" "B.Paste")
			(net "M_D_DQS_DN<13>")
		)
		(pad "101" smd rect
			(at 0 90.099896 270)
			(size 1.8034 0.508)
			(layers "B.Cu" "B.Mask" "B.Paste")
			(net "GND")
		)
		(pad "102" smd rect
			(at 0 90.950034 270)
			(size 1.8034 0.508)
			(layers "B.Cu" "B.Mask" "B.Paste")
			(net "M_D_DQ<38>")
		)
		(pad "103" smd rect
			(at 0 91.799918 270)
			(size 1.8034 0.508)
			(layers "B.Cu" "B.Mask" "B.Paste")
			(net "GND")
		)
		(pad "104" smd rect
			(at 0 92.650056 270)
			(size 1.8034 0.508)
			(layers "B.Cu" "B.Mask" "B.Paste")
			(net "M_D_DQ<34>")
		)
		(pad "105" smd rect
			(at 0 93.49994 270)
			(size 1.8034 0.508)
			(layers "B.Cu" "B.Mask" "B.Paste")
			(net "GND")
		)
		(pad "106" smd rect
			(at 0 94.350078 270)
			(size 1.8034 0.508)
			(layers "B.Cu" "B.Mask" "B.Paste")
			(net "M_D_DQ<44>")
		)
		(pad "107" smd rect
			(at 0 95.199962 270)
			(size 1.8034 0.508)
			(layers "B.Cu" "B.Mask" "B.Paste")
			(net "GND")
		)
		(pad "108" smd rect
			(at 0 96.0501 270)
			(size 1.8034 0.508)
			(layers "B.Cu" "B.Mask" "B.Paste")
			(net "M_D_DQ<40>")
		)
		(pad "109" smd rect
			(at 0 96.899984 270)
			(size 1.8034 0.508)
			(layers "B.Cu" "B.Mask" "B.Paste")
			(net "GND")
		)
		(pad "110" smd rect
			(at 0 97.750122 270)
			(size 1.8034 0.508)
			(layers "B.Cu" "B.Mask" "B.Paste")
			(net "M_D_DQS_DP<14>")
		)
		(pad "111" smd rect
			(at 0 98.600006 270)
			(size 1.8034 0.508)
			(layers "B.Cu" "B.Mask" "B.Paste")
			(net "M_D_DQS_DN<14>")
		)
		(pad "112" smd rect
			(at 0 99.44989 270)
			(size 1.8034 0.508)
			(layers "B.Cu" "B.Mask" "B.Paste")
			(net "GND")
		)
		(pad "113" smd rect
			(at 0 100.300028 270)
			(size 1.8034 0.508)
			(layers "B.Cu" "B.Mask" "B.Paste")
			(net "M_D_DQ<46>")
		)
		(pad "114" smd rect
			(at 0 101.149912 270)
			(size 1.8034 0.508)
			(layers "B.Cu" "B.Mask" "B.Paste")
			(net "GND")
		)
		(pad "115" smd rect
			(at 0 102.00005 270)
			(size 1.8034 0.508)
			(layers "B.Cu" "B.Mask" "B.Paste")
			(net "M_D_DQ<42>")
		)
		(pad "116" smd rect
			(at 0 102.849934 270)
			(size 1.8034 0.508)
			(layers "B.Cu" "B.Mask" "B.Paste")
			(net "GND")
		)
		(pad "117" smd rect
			(at 0 103.700072 270)
			(size 1.8034 0.508)
			(layers "B.Cu" "B.Mask" "B.Paste")
			(net "M_D_DQ<52>")
		)
		(pad "118" smd rect
			(at 0 104.549956 270)
			(size 1.8034 0.508)
			(layers "B.Cu" "B.Mask" "B.Paste")
			(net "GND")
		)
		(pad "119" smd rect
			(at 0 105.400094 270)
			(size 1.8034 0.508)
			(layers "B.Cu" "B.Mask" "B.Paste")
			(net "M_D_DQ<48>")
		)
		(pad "120" smd rect
			(at 0 106.249978 270)
			(size 1.8034 0.508)
			(layers "B.Cu" "B.Mask" "B.Paste")
			(net "GND")
		)
	)
)
